# S9S_MB_2U (Grand Teton) — schematic netlist excerpt (pin names and nets, part order shuffled) for the footprints in the layout excerpt that follows; sources: Cadence DE-HDL packaged netlist, KiCad conversion of 03242023_DA0F0TMBIJ0_F0T_Motherboard_J_brd_V01_OCP.brd

J8  SCONN288_ADR50017P087CC  SCONN288_ADR50017-P087CC IO  pkg DDR288S_1-1VXB  page 89
  VIN_BULK0  = P12V_S3_AUX_CPU0_NVDIMM
  RFU0  = TP_CHD_CPU0_DIMM2_FRU_0
  VIN_MGMT  = P3V3_AUX
  HSCL  = I3C_SPD_DDRABCD_CPU0_LVC1_SCL_7
  HSDA  = I3C_SPD_DDRABCD_CPU0_LVC1_SDA
  VSS0  = GND
  DQ0_A  = M_D_CPU0_SA_DQ<0>
  VSS1  = GND
  DQ1_A  = M_D_CPU0_SA_DQ<1>
  VSS2  = GND
  DQS0_A_T  = M_D_CPU0_SA_DQS_DP<0>
  DQS0_A_C  = M_D_CPU0_SA_DQS_DN<0>
  VSS3  = GND
  DQ4_A  = M_D_CPU0_SA_DQ<4>
  VSS4  = GND
  DQ5_A  = M_D_CPU0_SA_DQ<5>
  VSS5  = GND
  DQ8_A  = M_D_CPU0_SA_DQ<8>
  VSS6  = GND
  DQ9_A  = M_D_CPU0_SA_DQ<9>
  VSS7  = GND
  DQS1_A_T  = M_D_CPU0_SA_DQS_DP<1>
  DQS1_A_C  = M_D_CPU0_SA_DQS_DN<1>
  VSS8  = GND
  DQ12_A  = M_D_CPU0_SA_DQ<12>
  VSS9  = GND
  DQ13_A  = M_D_CPU0_SA_DQ<13>
  VSS10  = GND
  DQ16_A  = M_D_CPU0_SA_DQ<16>
  VSS11  = GND
  DQ17_A  = M_D_CPU0_SA_DQ<17>
  VSS12  = GND
  DQS2_A_T  = M_D_CPU0_SA_DQS_DP<2>
  DQS2_A_C  = M_D_CPU0_SA_DQS_DN<2>
  VSS13  = GND
  DQ20_A  = M_D_CPU0_SA_DQ<20>
  VSS14  = GND
  DQ21_A  = M_D_CPU0_SA_DQ<21>
  VSS15  = GND
  DQ24_A  = M_D_CPU0_SA_DQ<24>
  VSS16  = GND
  DQ25_A  = M_D_CPU0_SA_DQ<25>
  VSS17  = GND
  DQS3_A_T  = M_D_CPU0_SA_DQS_DP<3>
  DQS3_A_C  = M_D_CPU0_SA_DQS_DN<3>
  VSS18  = GND
  DQ28_A  = M_D_CPU0_SA_DQ<28>
  VSS19  = GND
  DQ29_A  = M_D_CPU0_SA_DQ<29>
  VSS20  = GND
  CB0_A  = M_D_CPU0_SA_CB<0>
  VSS21  = GND
  CB1_A  = M_D_CPU0_SA_CB<1>
  VSS22  = GND
  DQS4_A_T  = M_D_CPU0_SA_DQS_DP<4>
  DQS4_A_C  = M_D_CPU0_SA_DQS_DN<4>
  VSS23  = GND
  CB4_A  = M_D_CPU0_SA_CB<4>
  VSS24  = GND
  CB5_A  = M_D_CPU0_SA_CB<5>
  VSS25  = GND
  ALERT_N  = M_D_CPU0_ALERT_N
  VSS26  = GND
  CS0_A_N  = M_D_CPU0_SA_CS_N<2>
  VSS27  = GND
  CA0_A  = M_D_CPU0_SA_CA<0>
  VSS28  = GND
  CA2_A  = M_D_CPU0_SA_CA<2>
  VSS29  = GND
  CA4_A  = M_D_CPU0_SA_CA<4>
  VSS30  = GND
  CA6_A  = M_D_CPU0_SA_CA<6>
  VSS31  = GND
  PAR_A  = M_D_CPU0_SA_PAR
  VSS32  = GND
  CA0_B  = M_D_CPU0_SB_CA<0>
  VSS33  = GND
  CA2_B  = M_D_CPU0_SB_CA<2>
  VSS34  = GND
  CA4_B  = M_D_CPU0_SB_CA<4>
  VSS35  = GND
  CA6_B  = M_D_CPU0_SB_CA<6>
  VSS36  = GND
  CS0_B_N  = M_D_CPU0_SB_CS_N<2>
  VSS37  = GND
  \lbd||rsp_a_n\  = M_D_CPU0_SA_RSP<1>
  \lbs||rsp_b_n\  = M_D_CPU0_SB_RSP<1>
  VSS38  = GND
  CB4_B  = M_D_CPU0_SB_CB<4>
  VSS39  = GND
  CB5_B  = M_D_CPU0_SB_CB<5>
  VSS40  = GND
  \dqs9_b_t||tdqs9_b_t||dbi4_b_n\  = M_D_CPU0_SB_DQS_DP<9>
  \dqs9_b_c||tdqs9_b_c\  = M_D_CPU0_SB_DQS_DN<9>
  VSS41  = GND
  CB0_B  = M_D_CPU0_SB_CB<0>
  VSS42  = GND
  CB1_B  = M_D_CPU0_SB_CB<1>
  VSS43  = GND
  DQ0_B  = M_D_CPU0_SB_DQ<0>
  VSS44  = GND
  DQ1_B  = M_D_CPU0_SB_DQ<1>
  VSS45  = GND
  DQS0_B_T  = M_D_CPU0_SB_DQS_DP<0>
  DQS0_B_C  = M_D_CPU0_SB_DQS_DN<0>
  VSS46  = GND
  DQ4_B  = M_D_CPU0_SB_DQ<4>
  VSS47  = GND
  DQ5_B  = M_D_CPU0_SB_DQ<5>
  VSS48  = GND
  DQ8_B  = M_D_CPU0_SB_DQ<8>
  VSS49  = GND
  DQ9_B  = M_D_CPU0_SB_DQ<9>
  VSS50  = GND
  DQS1_B_T  = M_D_CPU0_SB_DQS_DP<1>
  DQS1_B_C  = M_D_CPU0_SB_DQS_DN<1>
  VSS51  = GND
  DQ12_B  = M_D_CPU0_SB_DQ<12>
  VSS52  = GND
  DQ13_B  = M_D_CPU0_SB_DQ<13>
  VSS53  = GND
  DQ16_B  = M_D_CPU0_SB_DQ<16>
  VSS54  = GND
  DQ17_B  = M_D_CPU0_SB_DQ<17>
  VSS55  = GND
  DQS2_B_T  = M_D_CPU0_SB_DQS_DP<2>
  DQS2_B_C  = M_D_CPU0_SB_DQS_DN<2>
  VSS56  = GND
  DQ20_B  = M_D_CPU0_SB_DQ<20>
  VSS57  = GND
  DQ21_B  = M_D_CPU0_SB_DQ<21>
  VSS58  = GND
  DQ24_B  = M_D_CPU0_SB_DQ<24>
  VSS59  = GND
  DQ25_B  = M_D_CPU0_SB_DQ<25>
  VSS60  = GND
  DQS3_B_T  = M_D_CPU0_SB_DQS_DP<3>
  DQS3_B_C  = M_D_CPU0_SB_DQS_DN<3>
  VSS61  = GND
  DQ28_B  = M_D_CPU0_SB_DQ<28>
  VSS62  = GND
  DQ29_B  = M_D_CPU0_SB_DQ<29>
  VSS63  = GND
  RFU1  = TP_CHD_CPU0_DIMM2_FRU_1
  VIN_BULK1  = P12V_S3_AUX_CPU0_NVDIMM
  VIN_BULK2  = P12V_S3_AUX_CPU0_NVDIMM
  \pwr_good||fail_n\  = PWRGD_CHD_CPU0_DIMM2
  HSA  = PD_CHD_CPU0_DIMM2_SAA
  RFU2  = TP_CHD_CPU0_DIMM2_FRU_2
  RFU3  = TP_CHD_CPU0_DIMM2_FRU_3
  VSS64  = GND
  DQ2_A  = M_D_CPU0_SA_DQ<2>
  VSS65  = GND
  DQ3_A  = M_D_CPU0_SA_DQ<3>
  VSS66  = GND
  \dqs5_a_c||tdqs5_a_c||dqs5_a_t||tdqs5_a_t\  = M_D_CPU0_SA_DQS_DN<5>
  \dqs5_a_t||tdqs5_a_t\  = M_D_CPU0_SA_DQS_DP<5>
  VSS67  = GND
  DQ6_A  = M_D_CPU0_SA_DQ<6>
  VSS68  = GND
  DQ7_A  = M_D_CPU0_SA_DQ<7>
  VSS69  = GND
  DQ10_A  = M_D_CPU0_SA_DQ<10>
  VSS70  = GND
  DQ11_A  = M_D_CPU0_SA_DQ<11>
  VSS71  = GND
  \dqs6_a_c||tdqs6_a_c||dqs6_a_t||tdqs6_a_t\  = M_D_CPU0_SA_DQS_DN<6>
  \dqs6_a_t||tdqs6_a_t\  = M_D_CPU0_SA_DQS_DP<6>
  VSS72  = GND
  DQ14_A  = M_D_CPU0_SA_DQ<14>
  VSS73  = GND
  DQ15_A  = M_D_CPU0_SA_DQ<15>
  VSS74  = GND
  DQ18_A  = M_D_CPU0_SA_DQ<18>
  VSS75  = GND
  DQ19_A  = M_D_CPU0_SA_DQ<19>
  VSS76  = GND
  \dqs7_a_c||tdqs7_a_c\  = M_D_CPU0_SA_DQS_DN<7>
  \dqs7_a_t||tdqs7_a_t\  = M_D_CPU0_SA_DQS_DP<7>
  VSS77  = GND
  DQ22_A  = M_D_CPU0_SA_DQ<22>
  VSS78  = GND
  DQ23_A  = M_D_CPU0_SA_DQ<23>
  VSS79  = GND
  DQ26_A  = M_D_CPU0_SA_DQ<26>
  VSS80  = GND
  DQ27_A  = M_D_CPU0_SA_DQ<27>
  VSS81  = GND
  \dqs8_a_c||tdqs8_a_c\  = M_D_CPU0_SA_DQS_DN<8>
  \dqs8_a_t||tdqs8_a_t\  = M_D_CPU0_SA_DQS_DP<8>
  VSS82  = GND
  DQ30_A  = M_D_CPU0_SA_DQ<30>
  VSS83  = GND
  DQ31_A  = M_D_CPU0_SA_DQ<31>
  VSS84  = GND
  CB2_A  = M_D_CPU0_SA_CB<2>
  VSS85  = GND
  CB3_A  = M_D_CPU0_SA_CB<3>
  VSS86  = GND
  \dqs9_a_c||tdqs9_a_c\  = M_D_CPU0_SA_DQS_DN<9>
  \dqs9_a_t||tdqs9_a_t\  = M_D_CPU0_SA_DQS_DP<9>
  VSS87  = GND
  CB6_A  = M_D_CPU0_SA_CB<6>
  VSS88  = GND
  CB7_A  = M_D_CPU0_SA_CB<7>
  VSS89  = GND
  RESET_N  = RST_M_CD_CPU0_FPGA_N
  VSS90  = GND
  CS1_A_N  = M_D_CPU0_SA_CS_N<3>
  VSS91  = GND
  CA1_A  = M_D_CPU0_SA_CA<1>
  VSS92  = GND
  CA3_A  = M_D_CPU0_SA_CA<3>
  VSS93  = GND
  CA5_A  = M_D_CPU0_SA_CA<5>
  VSS94  = GND
  CK_T  = M_D_CPU0_CLK_DP<1>
  CK_C  = M_D_CPU0_CLK_DN<1>
  VSS95  = GND
  RFU4  = TP_CHD_CPU0_DIMM2_FRU_4
  CA1_B  = M_D_CPU0_SB_CA<1>
  VSS96  = GND
  CA3_B  = M_D_CPU0_SB_CA<3>
  VSS97  = GND
  CA5_B  = M_D_CPU0_SB_CA<5>
  VSS98  = GND
  PAR_B  = M_D_CPU0_SB_PAR
  VSS99  = GND
  CS1_B_N  = M_D_CPU0_SB_CS_N<3>
  VSS100  = GND
  RFU5  = TP_CHD_CPU0_DIMM2_FRU_5
  RFU6  = TP_CHD_CPU0_DIMM2_FRU_6
  VSS101  = GND
  CB6_B  = M_D_CPU0_SB_CB<6>
  VSS102  = GND
  CB7_B  = M_D_CPU0_SB_CB<7>
  VSS103  = GND
  DQS4_B_C  = M_D_CPU0_SB_DQS_DN<4>
  DQS4_B_T  = M_D_CPU0_SB_DQS_DP<4>
  VSS104  = GND
  CB2_B  = M_D_CPU0_SB_CB<2>
  VSS105  = GND
  CB3_B  = M_D_CPU0_SB_CB<3>
  VSS106  = GND
  DQ2_B  = M_D_CPU0_SB_DQ<2>
  VSS107  = GND
  DQ3_B  = M_D_CPU0_SB_DQ<3>
  VSS108  = GND
  \dqs5_b_c||tdqs5_b_c\  = M_D_CPU0_SB_DQS_DN<5>
  \dqs5_b_t||tdqs5_b_t\  = M_D_CPU0_SB_DQS_DP<5>
  VSS109  = GND
  DQ6_B  = M_D_CPU0_SB_DQ<6>
  VSS110  = GND
  DQ7_B  = M_D_CPU0_SB_DQ<7>
  VSS111  = GND
  DQ10_B  = M_D_CPU0_SB_DQ<10>
  VSS112  = GND
  DQ11_B  = M_D_CPU0_SB_DQ<11>
  VSS113  = GND
  \dqs6_b_c||tdqs6_b_c\  = M_D_CPU0_SB_DQS_DN<6>
  \dqs6_b_t||tdqs6_b_t\  = M_D_CPU0_SB_DQS_DP<6>
  VSS114  = GND
  DQ14_B  = M_D_CPU0_SB_DQ<14>
  VSS115  = GND
  DQ15_B  = M_D_CPU0_SB_DQ<15>
  VSS116  = GND
  DQ18_B  = M_D_CPU0_SB_DQ<18>
  VSS117  = GND
  DQ19_B  = M_D_CPU0_SB_DQ<19>
  VSS118  = GND
  \dqs7_b_c||tdqs7_b_c\  = M_D_CPU0_SB_DQS_DN<7>
  \dqs7_b_t||tdqs7_b_t\  = M_D_CPU0_SB_DQS_DP<7>
  VSS119  = GND
  DQ22_B  = M_D_CPU0_SB_DQ<22>
  VSS120  = GND
  DQ23_B  = M_D_CPU0_SB_DQ<23>
  VSS121  = GND
  DQ26_B  = M_D_CPU0_SB_DQ<26>
  VSS122  = GND
  DQ27_B  = M_D_CPU0_SB_DQ<27>
  VSS123  = GND
  \dqs8_b_c||tdqs8_b_c\  = M_D_CPU0_SB_DQS_DN<8>
  \dqs8_b_t||tdqs8_b_t\  = M_D_CPU0_SB_DQS_DP<8>
  VSS124  = GND
  DQ30_B  = M_D_CPU0_SB_DQ<30>
  VSS125  = GND
  DQ31_B  = M_D_CPU0_SB_DQ<31>
  VSS126  = GND
  G1  = GND
  G2  = GND
  G3  = GND

(kicad_pcb
	(version 20260206)
	(generator "pcbnew")
	(generator_version "10.0")
	(general
		(thickness 1.6)
		(legacy_teardrops no)
	)
	(paper "A4")
	(title_block
		(title "03242023_DA0F0TMBIJ0_F0T_Motherboard_J_brd_V01_OCP.brd")
		(comment 1 "Grand Teton / footprint 652 of 6105 (J8), pads 229-274 of 291")
	)
	(layers
		(0 "F.Cu" signal "TOP")
		(4 "In1.Cu" signal "GND")
		(6 "In2.Cu" signal "IN1")
		(8 "In3.Cu" signal "GND1")
		(10 "In4.Cu" signal "IN2")
		(12 "In5.Cu" signal "GND2")
		(14 "In6.Cu" signal "IN3")
		(16 "In7.Cu" signal "GND3")
		(18 "In8.Cu" signal "VCC")
		(20 "In9.Cu" signal "VCC1")
		(22 "In10.Cu" signal "GND4")
		(24 "In11.Cu" signal "IN4")
		(26 "In12.Cu" signal "GND5")
		(28 "In13.Cu" signal "IN5")
		(30 "In14.Cu" signal "GND6")
		(32 "In15.Cu" signal "IN6")
		(34 "In16.Cu" signal "GND7")
		(2 "B.Cu" signal "BOTTOM")
		(9 "F.Adhes" user "F.Adhesive")
		(11 "B.Adhes" user "B.Adhesive")
		(13 "F.Paste" user "Package Geometry/Pastemask Top")
		(15 "B.Paste" user "Package Geometry/Pastemask Bottom")
		(5 "F.SilkS" user "Ref Des/Silkscreen Top")
		(7 "B.SilkS" user "Ref Des/Silkscreen Bottom")
		(1 "F.Mask" user "Board Geometry/Soldermask Top")
		(3 "B.Mask" user "Board Geometry/Soldermask Bottom")
		(17 "Dwgs.User" user "User.Drawings")
		(19 "Cmts.User" user "User.Comments")
		(21 "Eco1.User" user "User.Eco1")
		(23 "Eco2.User" user "User.Eco2")
		(25 "Edge.Cuts" user "Board Geometry/Outline")
		(27 "Margin" user)
		(31 "F.CrtYd" user "Package Geometry/Place Bound Top")
		(29 "B.CrtYd" user "Package Geometry/Place Bound Bottom")
		(35 "F.Fab" user "Ref Des/Assembly Top")
		(33 "B.Fab" user "Ref Des/Assembly Bottom")
	)
	(footprint ""
		(layer "F.Cu")
		(at 265.674348 -258.091686)
		(property "Reference" "J8"
			(at -3.683 -81.702148 0)
			(unlocked yes)
			(layer "F.SilkS")
			(effects
				(font
					(size 0.7874 0.5842)
					(thickness 0.1524)
				)
				(justify left)
			)
		)
		(property "Value" ""
			(at 0 0 0)
			(layer "F.Fab")
			(effects
				(font
					(size 1.27 1.27)
				)
			)
		)
		(duplicate_pad_numbers_are_jumpers no)
		(pad "229" smd rect
			(at 2.050034 13.17498 270)
			(size 0.519938 1.4986)
			(layers "F.Cu" "F.Mask" "F.Paste")
			(net "M_D_CPU0_SB_CS_N<3>")
		)
		(pad "230" smd rect
			(at 2.050034 14.025118 270)
			(size 0.519938 1.4986)
			(layers "F.Cu" "F.Mask" "F.Paste")
			(net "GND")
		)
		(pad "231" smd rect
			(at 2.050034 14.875002 270)
			(size 0.519938 1.4986)
			(layers "F.Cu" "F.Mask" "F.Paste")
			(net "TP_CHD_CPU0_DIMM2_FRU_5")
		)
		(pad "232" smd rect
			(at 2.050034 15.724886 270)
			(size 0.519938 1.4986)
			(layers "F.Cu" "F.Mask" "F.Paste")
			(net "TP_CHD_CPU0_DIMM2_FRU_6")
		)
		(pad "233" smd rect
			(at 2.050034 16.575024 270)
			(size 0.519938 1.4986)
			(layers "F.Cu" "F.Mask" "F.Paste")
			(net "GND")
		)
		(pad "234" smd rect
			(at 2.050034 17.424908 270)
			(size 0.519938 1.4986)
			(layers "F.Cu" "F.Mask" "F.Paste")
			(net "M_D_CPU0_SB_CB<6>")
		)
		(pad "235" smd rect
			(at 2.050034 18.275046 270)
			(size 0.519938 1.4986)
			(layers "F.Cu" "F.Mask" "F.Paste")
			(net "GND")
		)
		(pad "236" smd rect
			(at 2.050034 19.12493 270)
			(size 0.519938 1.4986)
			(layers "F.Cu" "F.Mask" "F.Paste")
			(net "M_D_CPU0_SB_CB<7>")
		)
		(pad "237" smd rect
			(at 2.050034 19.975068 270)
			(size 0.519938 1.4986)
			(layers "F.Cu" "F.Mask" "F.Paste")
			(net "GND")
		)
		(pad "238" smd rect
			(at 2.050034 20.824952 270)
			(size 0.519938 1.4986)
			(layers "F.Cu" "F.Mask" "F.Paste")
			(net "M_D_CPU0_SB_DQS_DN<4>")
		)
		(pad "239" smd rect
			(at 2.050034 21.67509 270)
			(size 0.519938 1.4986)
			(layers "F.Cu" "F.Mask" "F.Paste")
			(net "M_D_CPU0_SB_DQS_DP<4>")
		)
		(pad "240" smd rect
			(at 2.050034 22.524974 270)
			(size 0.519938 1.4986)
			(layers "F.Cu" "F.Mask" "F.Paste")
			(net "GND")
		)
		(pad "241" smd rect
			(at 2.050034 23.375112 270)
			(size 0.519938 1.4986)
			(layers "F.Cu" "F.Mask" "F.Paste")
			(net "M_D_CPU0_SB_CB<2>")
		)
		(pad "242" smd rect
			(at 2.050034 24.224996 270)
			(size 0.519938 1.4986)
			(layers "F.Cu" "F.Mask" "F.Paste")
			(net "GND")
		)
		(pad "243" smd rect
			(at 2.050034 25.07488 270)
			(size 0.519938 1.4986)
			(layers "F.Cu" "F.Mask" "F.Paste")
			(net "M_D_CPU0_SB_CB<3>")
		)
		(pad "244" smd rect
			(at 2.050034 25.925018 270)
			(size 0.519938 1.4986)
			(layers "F.Cu" "F.Mask" "F.Paste")
			(net "GND")
		)
		(pad "245" smd rect
			(at 2.050034 26.774902 270)
			(size 0.519938 1.4986)
			(layers "F.Cu" "F.Mask" "F.Paste")
			(net "M_D_CPU0_SB_DQ<2>")
		)
		(pad "246" smd rect
			(at 2.050034 27.62504 270)
			(size 0.519938 1.4986)
			(layers "F.Cu" "F.Mask" "F.Paste")
			(net "GND")
		)
		(pad "247" smd rect
			(at 2.050034 28.474924 270)
			(size 0.519938 1.4986)
			(layers "F.Cu" "F.Mask" "F.Paste")
			(net "M_D_CPU0_SB_DQ<3>")
		)
		(pad "248" smd rect
			(at 2.050034 29.325062 270)
			(size 0.519938 1.4986)
			(layers "F.Cu" "F.Mask" "F.Paste")
			(net "GND")
		)
		(pad "249" smd rect
			(at 2.050034 30.174946 270)
			(size 0.519938 1.4986)
			(layers "F.Cu" "F.Mask" "F.Paste")
			(net "M_D_CPU0_SB_DQS_DN<5>")
		)
		(pad "250" smd rect
			(at 2.050034 31.025084 270)
			(size 0.519938 1.4986)
			(layers "F.Cu" "F.Mask" "F.Paste")
			(net "M_D_CPU0_SB_DQS_DP<5>")
		)
		(pad "251" smd rect
			(at 2.050034 31.874968 270)
			(size 0.519938 1.4986)
			(layers "F.Cu" "F.Mask" "F.Paste")
			(net "GND")
		)
		(pad "252" smd rect
			(at 2.050034 32.725106 270)
			(size 0.519938 1.4986)
			(layers "F.Cu" "F.Mask" "F.Paste")
			(net "M_D_CPU0_SB_DQ<6>")
		)
		(pad "253" smd rect
			(at 2.050034 33.57499 270)
			(size 0.519938 1.4986)
			(layers "F.Cu" "F.Mask" "F.Paste")
			(net "GND")
		)
		(pad "254" smd rect
			(at 2.050034 34.425128 270)
			(size 0.519938 1.4986)
			(layers "F.Cu" "F.Mask" "F.Paste")
			(net "M_D_CPU0_SB_DQ<7>")
		)
		(pad "255" smd rect
			(at 2.050034 35.275012 270)
			(size 0.519938 1.4986)
			(layers "F.Cu" "F.Mask" "F.Paste")
			(net "GND")
		)
		(pad "256" smd rect
			(at 2.050034 36.124896 270)
			(size 0.519938 1.4986)
			(layers "F.Cu" "F.Mask" "F.Paste")
			(net "M_D_CPU0_SB_DQ<10>")
		)
		(pad "257" smd rect
			(at 2.050034 36.975034 270)
			(size 0.519938 1.4986)
			(layers "F.Cu" "F.Mask" "F.Paste")
			(net "GND")
		)
		(pad "258" smd rect
			(at 2.050034 37.824918 270)
			(size 0.519938 1.4986)
			(layers "F.Cu" "F.Mask" "F.Paste")
			(net "M_D_CPU0_SB_DQ<11>")
		)
		(pad "259" smd rect
			(at 2.050034 38.675056 270)
			(size 0.519938 1.4986)
			(layers "F.Cu" "F.Mask" "F.Paste")
			(net "GND")
		)
		(pad "260" smd rect
			(at 2.050034 39.52494 270)
			(size 0.519938 1.4986)
			(layers "F.Cu" "F.Mask" "F.Paste")
			(net "M_D_CPU0_SB_DQS_DN<6>")
		)
		(pad "261" smd rect
			(at 2.050034 40.375078 270)
			(size 0.519938 1.4986)
			(layers "F.Cu" "F.Mask" "F.Paste")
			(net "M_D_CPU0_SB_DQS_DP<6>")
		)
		(pad "262" smd rect
			(at 2.050034 41.224962 270)
			(size 0.519938 1.4986)
			(layers "F.Cu" "F.Mask" "F.Paste")
			(net "GND")
		)
		(pad "263" smd rect
			(at 2.050034 42.0751 270)
			(size 0.519938 1.4986)
			(layers "F.Cu" "F.Mask" "F.Paste")
			(net "M_D_CPU0_SB_DQ<14>")
		)
		(pad "264" smd rect
			(at 2.050034 42.924984 270)
			(size 0.519938 1.4986)
			(layers "F.Cu" "F.Mask" "F.Paste")
			(net "GND")
		)
		(pad "265" smd rect
			(at 2.050034 43.775122 270)
			(size 0.519938 1.4986)
			(layers "F.Cu" "F.Mask" "F.Paste")
			(net "M_D_CPU0_SB_DQ<15>")
		)
		(pad "266" smd rect
			(at 2.050034 44.625006 270)
			(size 0.519938 1.4986)
			(layers "F.Cu" "F.Mask" "F.Paste")
			(net "GND")
		)
		(pad "267" smd rect
			(at 2.050034 45.47489 270)
			(size 0.519938 1.4986)
			(layers "F.Cu" "F.Mask" "F.Paste")
			(net "M_D_CPU0_SB_DQ<18>")
		)
		(pad "268" smd rect
			(at 2.050034 46.325028 270)
			(size 0.519938 1.4986)
			(layers "F.Cu" "F.Mask" "F.Paste")
			(net "GND")
		)
		(pad "269" smd rect
			(at 2.050034 47.174912 270)
			(size 0.519938 1.4986)
			(layers "F.Cu" "F.Mask" "F.Paste")
			(net "M_D_CPU0_SB_DQ<19>")
		)
		(pad "270" smd rect
			(at 2.050034 48.02505 270)
			(size 0.519938 1.4986)
			(layers "F.Cu" "F.Mask" "F.Paste")
			(net "GND")
		)
		(pad "271" smd rect
			(at 2.050034 48.874934 270)
			(size 0.519938 1.4986)
			(layers "F.Cu" "F.Mask" "F.Paste")
			(net "M_D_CPU0_SB_DQS_DN<7>")
		)
		(pad "272" smd rect
			(at 2.050034 49.725072 270)
			(size 0.519938 1.4986)
			(layers "F.Cu" "F.Mask" "F.Paste")
			(net "M_D_CPU0_SB_DQS_DP<7>")
		)
		(pad "273" smd rect
			(at 2.050034 50.574956 270)
			(size 0.519938 1.4986)
			(layers "F.Cu" "F.Mask" "F.Paste")
			(net "GND")
		)
		(pad "274" smd rect
			(at 2.050034 51.425094 270)
			(size 0.519938 1.4986)
			(layers "F.Cu" "F.Mask" "F.Paste")
			(net "M_D_CPU0_SB_DQ<22>")
		)
	)
)
